# S9S_MB_2U (Grand Teton) — schematic netlist excerpt (pin names and nets, part order shuffled) for the footprints in the layout excerpt that follows; sources: Cadence DE-HDL packaged netlist, KiCad conversion of 03242023_DA0F0TMBIJ0_F0T_Motherboard_J_brd_V01_OCP.brd

R2417  Q_RES  33.2 1% CHIP  pkg 0402LF  page 240 : A = SMB_S3M_CPU_3V3AUX_SCL ; B = SMB_S3M_CPU_3V3AUX_SCL_R0
PR410  Q_RES  0 5% EMPTY  pkg 0402LF  page 296 : A = PVCCD_HV_CPU1_ISYS_R ; B = PVCCD_HV_CPU1_NVDIMM_ISENSE
C165  Q_CAP_DIFFBUS  DIFF BUS_0.22UF 6.3V 20% X6S  pkg C0201  page 178 : \1\ = DMI_CPU0_PCH_RX_C_DN<2> ; \2\ = DMI_CPU0_PCH_RX_DN<2>

(kicad_pcb
	(version 20260206)
	(generator "pcbnew")
	(generator_version "10.0")
	(general
		(thickness 1.6)
		(legacy_teardrops no)
	)
	(paper "A4")
	(title_block
		(title "03242023_DA0F0TMBIJ0_F0T_Motherboard_J_brd_V01_OCP.brd")
		(comment 1 "Grand Teton / footprints 4278-4280 of 6105")
	)
	(layers
		(0 "F.Cu" signal "TOP")
		(4 "In1.Cu" signal "GND")
		(6 "In2.Cu" signal "IN1")
		(8 "In3.Cu" signal "GND1")
		(10 "In4.Cu" signal "IN2")
		(12 "In5.Cu" signal "GND2")
		(14 "In6.Cu" signal "IN3")
		(16 "In7.Cu" signal "GND3")
		(18 "In8.Cu" signal "VCC")
		(20 "In9.Cu" signal "VCC1")
		(22 "In10.Cu" signal "GND4")
		(24 "In11.Cu" signal "IN4")
		(26 "In12.Cu" signal "GND5")
		(28 "In13.Cu" signal "IN5")
		(30 "In14.Cu" signal "GND6")
		(32 "In15.Cu" signal "IN6")
		(34 "In16.Cu" signal "GND7")
		(2 "B.Cu" signal "BOTTOM")
		(9 "F.Adhes" user "F.Adhesive")
		(11 "B.Adhes" user "B.Adhesive")
		(13 "F.Paste" user "Package Geometry/Pastemask Top")
		(15 "B.Paste" user "Package Geometry/Pastemask Bottom")
		(5 "F.SilkS" user "Ref Des/Silkscreen Top")
		(7 "B.SilkS" user "Ref Des/Silkscreen Bottom")
		(1 "F.Mask" user "Board Geometry/Soldermask Top")
		(3 "B.Mask" user "Board Geometry/Soldermask Bottom")
		(17 "Dwgs.User" user "User.Drawings")
		(19 "Cmts.User" user "User.Comments")
		(21 "Eco1.User" user "User.Eco1")
		(23 "Eco2.User" user "User.Eco2")
		(25 "Edge.Cuts" user "Board Geometry/Outline")
		(27 "Margin" user)
		(31 "F.CrtYd" user "Package Geometry/Place Bound Top")
		(29 "B.CrtYd" user "Package Geometry/Place Bound Bottom")
		(35 "F.Fab" user "Ref Des/Assembly Top")
		(33 "B.Fab" user "Ref Des/Assembly Bottom")
	)
	(footprint ""
		(layer "B.Cu")
		(at 31.9024 -164.292788 180)
		(property "Reference" "PR410"
			(at 0 0 0)
			(layer "B.SilkS")
			(hide yes)
			(effects
				(font
					(size 1.27 1.27)
				)
				(justify mirror)
			)
		)
		(property "Value" ""
			(at 0 0 0)
			(layer "B.Fab")
			(effects
				(font
					(size 1.27 1.27)
				)
				(justify mirror)
			)
		)
		(duplicate_pad_numbers_are_jumpers no)
		(fp_line
			(start 0.7874 0.4064)
			(end 0.7874 -0.4064)
			(stroke
				(width 0.1524)
				(type default)
			)
			(layer "B.SilkS")
		)
		(fp_line
			(start 0.7874 -0.4064)
			(end -0.7874 -0.4064)
			(stroke
				(width 0.1524)
				(type default)
			)
			(layer "B.SilkS")
		)
		(fp_line
			(start -0.7874 0.4064)
			(end 0.7874 0.4064)
			(stroke
				(width 0.1524)
				(type default)
			)
			(layer "B.SilkS")
		)
		(fp_line
			(start -0.7874 -0.4064)
			(end -0.7874 0.4064)
			(stroke
				(width 0.1524)
				(type default)
			)
			(layer "B.SilkS")
		)
		(fp_line
			(start 0.67945 0.3048)
			(end 0.67945 -0.305054)
			(stroke
				(width 0.1)
				(type default)
			)
			(layer "B.Fab")
		)
		(fp_line
			(start 0.67945 -0.305054)
			(end 0.12065 -0.305054)
			(stroke
				(width 0.1)
				(type default)
			)
			(layer "B.Fab")
		)
		(fp_line
			(start 0.12065 0.3048)
			(end 0.67945 0.3048)
			(stroke
				(width 0.1)
				(type default)
			)
			(layer "B.Fab")
		)
		(fp_line
			(start 0.12065 0.2794)
			(end 0.12065 0.3048)
			(stroke
				(width 0.1)
				(type default)
			)
			(layer "B.Fab")
		)
		(fp_line
			(start 0.12065 -0.2794)
			(end -0.12065 -0.2794)
			(stroke
				(width 0.1)
				(type default)
			)
			(layer "B.Fab")
		)
		(fp_line
			(start 0.12065 -0.305054)
			(end 0.12065 -0.2794)
			(stroke
				(width 0.1)
				(type default)
			)
			(layer "B.Fab")
		)
		(fp_line
			(start -0.120396 0.3048)
			(end -0.120396 0.2794)
			(stroke
				(width 0.1)
				(type default)
			)
			(layer "B.Fab")
		)
		(fp_line
			(start -0.120396 0.2794)
			(end 0.12065 0.2794)
			(stroke
				(width 0.1)
				(type default)
			)
			(layer "B.Fab")
		)
		(fp_line
			(start -0.12065 -0.2794)
			(end -0.12065 -0.3048)
			(stroke
				(width 0.1)
				(type default)
			)
			(layer "B.Fab")
		)
		(fp_line
			(start -0.12065 -0.3048)
			(end -0.67945 -0.3048)
			(stroke
				(width 0.1)
				(type default)
			)
			(layer "B.Fab")
		)
		(fp_line
			(start -0.67945 0.3048)
			(end -0.120396 0.3048)
			(stroke
				(width 0.1)
				(type default)
			)
			(layer "B.Fab")
		)
		(fp_line
			(start -0.67945 -0.3048)
			(end -0.67945 0.3048)
			(stroke
				(width 0.1)
				(type default)
			)
			(layer "B.Fab")
		)
		(pad "1" smd circle
			(at 0.40005 0)
			(size 0 0)
			(layers "B.Cu" "B.Mask" "B.Paste")
			(net "PVCCD_HV_CPU1_ISYS_R")
		)
		(pad "2" smd circle
			(at -0.40005 0)
			(size 0 0)
			(layers "B.Cu" "B.Mask" "B.Paste")
			(net "PVCCD_HV_CPU1_NVDIMM_ISENSE")
		)
	)
	(footprint ""
		(layer "B.Cu")
		(at 340.406228 -62.056264 90)
		(property "Reference" "C165"
			(at 0 0 90)
			(layer "B.SilkS")
			(hide yes)
			(effects
				(font
					(size 1.27 1.27)
				)
				(justify mirror)
			)
		)
		(property "Value" ""
			(at 0 0 90)
			(layer "B.Fab")
			(effects
				(font
					(size 1.27 1.27)
				)
				(justify mirror)
			)
		)
		(duplicate_pad_numbers_are_jumpers no)
		(fp_line
			(start 0.299974 -0.150114)
			(end -0.299974 -0.150114)
			(stroke
				(width 0.1)
				(type default)
			)
			(layer "B.Fab")
		)
		(fp_line
			(start -0.299974 -0.150114)
			(end -0.299974 0.150114)
			(stroke
				(width 0.1)
				(type default)
			)
			(layer "B.Fab")
		)
		(fp_line
			(start 0.299974 0.150114)
			(end 0.299974 -0.150114)
			(stroke
				(width 0.1)
				(type default)
			)
			(layer "B.Fab")
		)
		(fp_line
			(start -0.299974 0.150114)
			(end 0.299974 0.150114)
			(stroke
				(width 0.1)
				(type default)
			)
			(layer "B.Fab")
		)
		(pad "1" smd rect
			(at 0.2667 0 270)
			(size 0.3048 0.381)
			(layers "B.Cu" "B.Mask" "B.Paste")
			(net "DMI_CPU0_PCH_RX_C_DN<2>")
		)
		(pad "2" smd rect
			(at -0.2667 0 270)
			(size 0.3048 0.381)
			(layers "B.Cu" "B.Mask" "B.Paste")
			(net "DMI_CPU0_PCH_RX_DN<2>")
		)
	)
	(footprint ""
		(layer "B.Cu")
		(at 151.99487 -13.762228 90)
		(property "Reference" "R2417"
			(at 0 0 90)
			(layer "B.SilkS")
			(hide yes)
			(effects
				(font
					(size 1.27 1.27)
				)
				(justify mirror)
			)
		)
		(property "Value" ""
			(at 0 0 90)
			(layer "B.Fab")
			(effects
				(font
					(size 1.27 1.27)
				)
				(justify mirror)
			)
		)
		(duplicate_pad_numbers_are_jumpers no)
		(fp_line
			(start 0.7874 -0.4064)
			(end -0.7874 -0.4064)
			(stroke
				(width 0.1524)
				(type default)
			)
			(layer "B.SilkS")
		)
		(fp_line
			(start -0.7874 -0.4064)
			(end -0.7874 0.4064)
			(stroke
				(width 0.1524)
				(type default)
			)
			(layer "B.SilkS")
		)
		(fp_line
			(start 0.7874 0.4064)
			(end 0.7874 -0.4064)
			(stroke
				(width 0.1524)
				(type default)
			)
			(layer "B.SilkS")
		)
		(fp_line
			(start -0.7874 0.4064)
			(end 0.7874 0.4064)
			(stroke
				(width 0.1524)
				(type default)
			)
			(layer "B.SilkS")
		)
		(fp_line
			(start 0.67945 -0.305054)
			(end 0.12065 -0.305054)
			(stroke
				(width 0.1)
				(type default)
			)
			(layer "B.Fab")
		)
		(fp_line
			(start 0.12065 -0.305054)
			(end 0.12065 -0.2794)
			(stroke
				(width 0.1)
				(type default)
			)
			(layer "B.Fab")
		)
		(fp_line
			(start -0.12065 -0.3048)
			(end -0.67945 -0.3048)
			(stroke
				(width 0.1)
				(type default)
			)
			(layer "B.Fab")
		)
		(fp_line
			(start -0.67945 -0.3048)
			(end -0.67945 0.3048)
			(stroke
				(width 0.1)
				(type default)
			)
			(layer "B.Fab")
		)
		(fp_line
			(start 0.12065 -0.2794)
			(end -0.12065 -0.2794)
			(stroke
				(width 0.1)
				(type default)
			)
			(layer "B.Fab")
		)
		(fp_line
			(start -0.12065 -0.2794)
			(end -0.12065 -0.3048)
			(stroke
				(width 0.1)
				(type default)
			)
			(layer "B.Fab")
		)
		(fp_line
			(start 0.12065 0.2794)
			(end 0.12065 0.3048)
			(stroke
				(width 0.1)
				(type default)
			)
			(layer "B.Fab")
		)
		(fp_line
			(start -0.120396 0.2794)
			(end 0.12065 0.2794)
			(stroke
				(width 0.1)
				(type default)
			)
			(layer "B.Fab")
		)
		(fp_line
			(start 0.67945 0.3048)
			(end 0.67945 -0.305054)
			(stroke
				(width 0.1)
				(type default)
			)
			(layer "B.Fab")
		)
		(fp_line
			(start 0.12065 0.3048)
			(end 0.67945 0.3048)
			(stroke
				(width 0.1)
				(type default)
			)
			(layer "B.Fab")
		)
		(fp_line
			(start -0.120396 0.3048)
			(end -0.120396 0.2794)
			(stroke
				(width 0.1)
				(type default)
			)
			(layer "B.Fab")
		)
		(fp_line
			(start -0.67945 0.3048)
			(end -0.120396 0.3048)
			(stroke
				(width 0.1)
				(type default)
			)
			(layer "B.Fab")
		)
		(pad "1" smd circle
			(at 0.40005 0 270)
			(size 0 0)
			(layers "B.Cu" "B.Mask" "B.Paste")
			(net "SMB_S3M_CPU_3V3AUX_SCL")
		)
		(pad "2" smd circle
			(at -0.40005 0 270)
			(size 0 0)
			(layers "B.Cu" "B.Mask" "B.Paste")
			(net "SMB_S3M_CPU_3V3AUX_SCL_R0")
		)
	)
)
